FILE_TYPE = MACRO_DRAWING;
SET COLOR_WIRE YELLOW;
SET COLOR_PROP ORANGE;
SET COLOR_DOT WHITE;
SET COLOR_ARC YELLOW;
SET COLOR_BODY GREEN;
SET COLOR_NOTE PURPLE;
SET PROP_DISPLAY VALUE;
SET PAGE_NUMBER P36;
FORCEADD QUANTA_TITLE_BLOCK_C..1
(0 0);
FORCEPROP 1 LAST CUSTOM_TXT_CDS <NAME_2>
J 0
(-3175 50);
FORCEPROP 1 LAST CUSTOM_TXT_CDS <NAME_1>
J 0
(-3175 175);
FORCEPROP 1 LAST CUSTOM_TXT_CDS <Q_NUMBER>
J 0
(-1403 103);
DISPLAY 1.212766 (-1403 103);
FORCEPROP 1 LAST CUSTOM_TXT_CDS <Q_PROJ>
J 0
(-2382 102);
DISPLAY 1.212766 (-2382 102);
FORCEPROP 1 LAST CUSTOM_TXT_CDS <Q_REV>
J 0
(-184 103);
DISPLAY 1.212766 (-184 103);
FORCEPROP 1 LAST CUSTOM_TXT_CDS <CON_LAST_MODIFIED>
J 0
(-1885 15);
DISPLAY 0.978723 (-1885 15);
FORCEPROP 1 LAST CUSTOM_TXT_CDS <CON_PAGE_NUM> OF <CON_TOTAL_PAGES>
J 0
(-446 18);
DISPLAY 0.978723 (-446 18);
FORCEPROP 1 LAST Q_TITLE Blank
J 0
(-9300 50);
DISPLAY 2.446809 (-9300 50);
PAINT GREEN (-9300 50);
FORCEPROP 1 LAST CDS_LMAN_SYM_OUTLINE -9475,6775,100,-125
J 0
(0 0);
DISPLAY 0.468085 (0 0);
PAINT GREEN (0 0);
DISPLAY INVISIBLE (0 0);
FORCEPROP 2 LAST CDS_LIB pure_quanta
J 0
(0 0);
DISPLAY INVISIBLE (0 0);
FORCEPROP 2 LAST PAGE_BORDER TRUE
J 0
(-7890 5250);
DISPLAY 0.638298 (-7890 5250);
PAINT PINK (-7890 5250);
DISPLAY INVISIBLE (-7890 5250);
FORCEPROP 2 LAST CDS_XR_PAGE_TITLE CR-36 : @T6G_MB_LIB.T6G(SCH_1):PAGE36
J 0
(-7890 5250);
DISPLAY 0.638298 (-7890 5250);
PAINT PINK (-7890 5250);
DISPLAY INVISIBLE (-7890 5250);
FORCEPROP 2 LAST CUSTOM_TXT_CDS <XR_PAGE_TITLE>
J 0
(-7890 5250);
DISPLAY 0.638298 (-7890 5250);
PAINT PINK (-7890 5250);
DISPLAY INVISIBLE (-7890 5250);
FORCEPROP 1 LAST COMMENT_BODY TRUE
J 0
(12 -13);
DISPLAY 0.978723 (12 -13);
PAINT GREEN (12 -13);
DISPLAY INVISIBLE (12 -13);
FORCEPROP 1 LAST Q_DEPT BU9
J 1
(-3763 49);
DISPLAY 1.957447 (-3763 49);
PAINT GREEN (-3763 49);
DISPLAY INVISIBLE (-3763 49);
FORCEPROP 0 LAST CDS_CON_LAST_MODIFIED Thu Aug 24 10:13:43 2023
J 0
(-1885 15);
DISPLAY INVISIBLE (-1885 15);
QUIT
